FILE_TYPE = CONNECTIVITY;
{Allegro Design Entry HDL 17.4-2019 S026 (4007227) 1/17/2022}
"PAGE_NUMBER" = 394;
0"NC";
1"P5E_CPU1_P1_RX_BUF_DN<7:0>";
2"P5E_CPU1_P1_RX_BUF_DP<7:0>";
3"P5E_CPU1_P1_RX_BUF_DN<15:8>";
4"P5E_CPU1_P1_RX_BUF_DP<15:8>";
5"P5E_CPU1_P1_RX_BUF_DP<11>";
6"P5E_CPU1_P1_RX_BUF_DP<1>";
7"P5E_CPU1_P1_RX_BUF_DP<2>";
8"P5E_CPU1_P1_RX_BUF_DP<9>";
9"P5E_CPU1_P1_RX_BUF_DP<12>";
10"P5E_CPU1_P1_RX_BUF_DP<13>";
11"P5E_CPU1_P1_RX_BUF_DP<14>";
12"P5E_CPU1_P1_RX_BUF_DP<8>";
13"P5E_CPU1_P1_RX_BUF_DN<9>";
14"P5E_CPU1_P1_RX_BUF_DP<10>";
15"P5E_CPU1_P1_RX_BUF_DN<11>";
16"P5E_CPU1_P1_RX_BUF_DN<13>";
17"P5E_CPU1_P1_RX_BUF_DN<8>";
18"P5E_CPU1_P1_RX_BUF_DP<15>";
19"P5E_CPU1_P1_RX_BUF_DP<0>";
20"P5E_CPU1_P1_RX_BUF_DN<1>";
21"P5E_CPU1_P1_RX_BUF_DP<3>";
22"P5E_CPU1_P1_RX_BUF_DP<4>";
23"P5E_CPU1_P1_RX_BUF_DP<5>";
24"P5E_CPU1_P1_RX_BUF_DN<0>";
25"P5E_CPU1_P1_RX_BUF_DP<7>";
26"P5E_CPU1_P1_RX_BUF_DN<15>";
27"P5E_CPU1_P1_RX_BUF_DN<14>";
28"P5E_CPU1_P1_RX_BUF_DN<12>";
29"P5E_CPU1_P1_RX_BUF_DN<10>";
30"P5E_CPU1_P1_RX_BUF_DN<7>";
31"P5E_CPU1_P1_RX_BUF_DP<6>";
32"P5E_CPU1_P1_RX_BUF_DN<6>";
33"P5E_CPU1_P1_RX_BUF_DN<5>";
34"P5E_CPU1_P1_RX_BUF_DN<4>";
35"P5E_CPU1_P1_RX_BUF_DN<2>";
36"P5E_CPU1_P1_RX_BUF_DN<3>";
%"PT5161LRS"
"1","(-7525,3875)","0","pure_quanta","I1";
;
LOCATION"U6015"
$SEC"1"
CDS_SEC"1"
PART_TYPE"SMLF"
MATERIAL"IC"
VALUE"PT5161LRS"
CDS_LIB"pure_quanta"
CDS_LMAN_SYM_OUTLINE"-350,1450,300,-1400"
NEEDS_NO_SIZE"TRUE"
PART_NUMBER"AJ051610U03";
"A_PERN7"
$PN"CB2"17;
"A_PERP7"
$PN"CD1"12;
"A_PERN6"
$PN"BR2"13;
"A_PERP6"
$PN"BU1"8;
"A_PERN5"
$PN"BH2"29;
"A_PERP5"
$PN"BK1"14;
"A_PERN4"
$PN"BA2"15;
"A_PERP4"
$PN"BC1"5;
"A_PERN3"
$PN"AP2"28;
"A_PERP3"
$PN"AT1"9;
"A_PERN2"
$PN"AG2"16;
"A_PERP2"
$PN"AJ1"10;
"A_PERN1"
$PN"Y2"27;
"A_PERP1"
$PN"AB1"11;
"A_PERN0"
$PN"N2"26;
"A_PERP0"
$PN"R1"18;
%"TAP"
"1","(-6300,3625)","0","standard","I10";
;
CDS_LIB"standard"
BODY_TYPE"PLUMBING"
HDL_TAP"TRUE";
"B \NAC \NWC"3;
"S \NAC"
BN"11"15;
%"TAP"
"1","(-6300,3975)","0","standard","I11";
;
CDS_LIB"standard"
BODY_TYPE"PLUMBING"
HDL_TAP"TRUE";
"B \NAC \NWC"3;
"S \NAC"
BN"12"28;
%"TAP"
"1","(-6500,5125)","0","standard","I12";
;
CDS_LIB"standard"
BODY_TYPE"PLUMBING"
HDL_TAP"TRUE";
"B \NAC \NWC"4;
"S \NAC"
BN"15"18;
%"TAP"
"1","(-6500,4775)","0","standard","I13";
;
CDS_LIB"standard"
BODY_TYPE"PLUMBING"
HDL_TAP"TRUE";
"B \NAC \NWC"4;
"S \NAC"
BN"14"11;
%"TAP"
"1","(-6500,4425)","0","standard","I14";
;
CDS_LIB"standard"
BODY_TYPE"PLUMBING"
HDL_TAP"TRUE";
"B \NAC \NWC"4;
"S \NAC"
BN"13"10;
%"TAP"
"1","(-6300,4325)","0","standard","I15";
;
CDS_LIB"standard"
BODY_TYPE"PLUMBING"
HDL_TAP"TRUE";
"B \NAC \NWC"3;
"S \NAC"
BN"13"16;
%"TAP"
"1","(-6300,4675)","0","standard","I16";
;
CDS_LIB"standard"
BODY_TYPE"PLUMBING"
HDL_TAP"TRUE";
"B \NAC \NWC"3;
"S \NAC"
BN"14"27;
%"TAP"
"1","(-6300,5025)","0","standard","I17";
;
CDS_LIB"standard"
BODY_TYPE"PLUMBING"
HDL_TAP"TRUE";
"B \NAC \NWC"3;
"S \NAC"
BN"15"26;
%"TAP"
"1","(-6500,3025)","0","standard","I2";
;
CDS_LIB"standard"
BODY_TYPE"PLUMBING"
HDL_TAP"TRUE";
"B \NAC \NWC"4;
"S \NAC"
BN"9"8;
%"TAP"
"1","(-1850,2600)","0","standard","I20";
;
CDS_LIB"standard"
BODY_TYPE"PLUMBING"
HDL_TAP"TRUE";
"B \NAC \NWC"1;
"S \NAC"
BN"0"24;
%"TAP"
"1","(-2050,2700)","0","standard","I21";
;
CDS_LIB"standard"
BODY_TYPE"PLUMBING"
HDL_TAP"TRUE";
"B \NAC \NWC"2;
"S \NAC"
BN"0"19;
%"TAP"
"1","(-2050,3050)","0","standard","I22";
;
CDS_LIB"standard"
BODY_TYPE"PLUMBING"
HDL_TAP"TRUE";
"B \NAC \NWC"2;
"S \NAC"
BN"1"6;
%"TAP"
"1","(-1850,2950)","0","standard","I23";
;
CDS_LIB"standard"
BODY_TYPE"PLUMBING"
HDL_TAP"TRUE";
"B \NAC \NWC"1;
"S \NAC"
BN"1"20;
%"TAP"
"1","(-2050,3400)","0","standard","I24";
;
CDS_LIB"standard"
BODY_TYPE"PLUMBING"
HDL_TAP"TRUE";
"B \NAC \NWC"2;
"S \NAC"
BN"2"7;
%"TAP"
"1","(-1850,3300)","0","standard","I25";
;
CDS_LIB"standard"
BODY_TYPE"PLUMBING"
HDL_TAP"TRUE";
"B \NAC \NWC"1;
"S \NAC"
BN"2"35;
%"TAP"
"1","(-1850,3650)","0","standard","I26";
;
CDS_LIB"standard"
BODY_TYPE"PLUMBING"
HDL_TAP"TRUE";
"B \NAC \NWC"1;
"S \NAC"
BN"3"36;
%"TAP"
"1","(-2050,3750)","0","standard","I27";
;
CDS_LIB"standard"
BODY_TYPE"PLUMBING"
HDL_TAP"TRUE";
"B \NAC \NWC"2;
"S \NAC"
BN"3"21;
%"TAP"
"1","(-2050,4100)","0","standard","I28";
;
CDS_LIB"standard"
BODY_TYPE"PLUMBING"
HDL_TAP"TRUE";
"B \NAC \NWC"2;
"S \NAC"
BN"4"22;
%"TAP"
"1","(-1850,4000)","0","standard","I29";
;
CDS_LIB"standard"
BODY_TYPE"PLUMBING"
HDL_TAP"TRUE";
"B \NAC \NWC"1;
"S \NAC"
BN"4"34;
%"TAP"
"1","(-6500,2675)","0","standard","I3";
;
CDS_LIB"standard"
BODY_TYPE"PLUMBING"
HDL_TAP"TRUE";
"B \NAC \NWC"4;
"S \NAC"
BN"8"12;
%"TAP"
"1","(-2050,4450)","0","standard","I30";
;
CDS_LIB"standard"
BODY_TYPE"PLUMBING"
HDL_TAP"TRUE";
"B \NAC \NWC"2;
"S \NAC"
BN"5"23;
%"TAP"
"1","(-1850,4350)","0","standard","I31";
;
CDS_LIB"standard"
BODY_TYPE"PLUMBING"
HDL_TAP"TRUE";
"B \NAC \NWC"1;
"S \NAC"
BN"5"33;
%"TAP"
"1","(-1850,4700)","0","standard","I32";
;
CDS_LIB"standard"
BODY_TYPE"PLUMBING"
HDL_TAP"TRUE";
"B \NAC \NWC"1;
"S \NAC"
BN"6"32;
%"TAP"
"1","(-2050,4800)","0","standard","I33";
;
CDS_LIB"standard"
BODY_TYPE"PLUMBING"
HDL_TAP"TRUE";
"B \NAC \NWC"2;
"S \NAC"
BN"6"31;
%"TAP"
"1","(-2050,5150)","0","standard","I34";
;
CDS_LIB"standard"
BODY_TYPE"PLUMBING"
HDL_TAP"TRUE";
"B \NAC \NWC"2;
"S \NAC"
BN"7"25;
%"TAP"
"1","(-1850,5050)","0","standard","I35";
;
CDS_LIB"standard"
BODY_TYPE"PLUMBING"
HDL_TAP"TRUE";
"B \NAC \NWC"1;
"S \NAC"
BN"7"30;
%"PT5161LRS"
"2","(-3075,3900)","0","pure_quanta","I38";
;
LOCATION"U6015"
$SEC"2"
CDS_SEC"2"
VALUE"PT5161LRS"
MATERIAL"IC"
PART_TYPE"SMLF"
NEEDS_NO_SIZE"TRUE"
CDS_LMAN_SYM_OUTLINE"-350,1450,300,-1400"
CDS_LIB"pure_quanta"
PART_NUMBER"AJ051610U03";
"A_PERN15"
$PN"EV2"24;
"A_PERP15"
$PN"EY1"19;
"A_PERN14"
$PN"EL2"20;
"A_PERP14"
$PN"EN1"6;
"A_PERN13"
$PN"ED2"35;
"A_PERP13"
$PN"EF1"7;
"A_PERN12"
$PN"DU2"36;
"A_PERP12"
$PN"DW1"21;
"A_PERN11"
$PN"DK2"34;
"A_PERP11"
$PN"DM1"22;
"A_PERN10"
$PN"DC2"33;
"A_PERP10"
$PN"DE1"23;
"A_PERN9"
$PN"CT2"32;
"A_PERP9"
$PN"CV1"31;
"A_PERN8"
$PN"CJ2"30;
"A_PERP8"
$PN"CL1"25;
%"TAP"
"1","(-6300,2575)","0","standard","I4";
;
CDS_LIB"standard"
BODY_TYPE"PLUMBING"
HDL_TAP"TRUE";
"B \NAC \NWC"3;
"S \NAC"
BN"8"17;
%"TAP"
"1","(-6300,2925)","0","standard","I5";
;
CDS_LIB"standard"
BODY_TYPE"PLUMBING"
HDL_TAP"TRUE";
"B \NAC \NWC"3;
"S \NAC"
BN"9"13;
%"TAP"
"1","(-6500,3725)","0","standard","I6";
;
CDS_LIB"standard"
BODY_TYPE"PLUMBING"
HDL_TAP"TRUE";
"B \NAC \NWC"4;
"S \NAC"
BN"11"5;
%"TAP"
"1","(-6500,3375)","0","standard","I7";
;
CDS_LIB"standard"
BODY_TYPE"PLUMBING"
HDL_TAP"TRUE";
"B \NAC \NWC"4;
"S \NAC"
BN"10"14;
%"TAP"
"1","(-6500,4075)","0","standard","I8";
;
CDS_LIB"standard"
BODY_TYPE"PLUMBING"
HDL_TAP"TRUE";
"B \NAC \NWC"4;
"S \NAC"
BN"12"9;
%"TAP"
"1","(-6300,3275)","0","standard","I9";
;
CDS_LIB"standard"
BODY_TYPE"PLUMBING"
HDL_TAP"TRUE";
"B \NAC \NWC"3;
"S \NAC"
BN"10"29;
END.
